# S9S_MB_2U (Grand Teton) — schematic netlist excerpt (pin names and nets, part order shuffled) for the footprints in the layout excerpt that follows; sources: Cadence DE-HDL packaged netlist, KiCad conversion of 03242023_DA0F0TMBIJ0_F0T_Motherboard_J_brd_V01_OCP.brd

PC2279  Q_CAP  0.01UF 25V 10% X7R  pkg 0402  page 262 : A = SH_P1V05_PCH_AUX_P ; B = SH_P1V05_PCH_AUX_N
PC117  Q_CAPP  330UF 2V 35% SPCAP  pkg SMLF  page 262 : A = P1V05_PCH_AUX ; B = GND

(kicad_pcb
	(version 20260206)
	(generator "pcbnew")
	(generator_version "10.0")
	(general
		(thickness 1.6)
		(legacy_teardrops no)
	)
	(paper "A4")
	(title_block
		(title "03242023_DA0F0TMBIJ0_F0T_Motherboard_J_brd_V01_OCP.brd")
		(comment 1 "Grand Teton / footprints 2124-2125 of 6105")
	)
	(layers
		(0 "F.Cu" signal "TOP")
		(4 "In1.Cu" signal "GND")
		(6 "In2.Cu" signal "IN1")
		(8 "In3.Cu" signal "GND1")
		(10 "In4.Cu" signal "IN2")
		(12 "In5.Cu" signal "GND2")
		(14 "In6.Cu" signal "IN3")
		(16 "In7.Cu" signal "GND3")
		(18 "In8.Cu" signal "VCC")
		(20 "In9.Cu" signal "VCC1")
		(22 "In10.Cu" signal "GND4")
		(24 "In11.Cu" signal "IN4")
		(26 "In12.Cu" signal "GND5")
		(28 "In13.Cu" signal "IN5")
		(30 "In14.Cu" signal "GND6")
		(32 "In15.Cu" signal "IN6")
		(34 "In16.Cu" signal "GND7")
		(2 "B.Cu" signal "BOTTOM")
		(9 "F.Adhes" user "F.Adhesive")
		(11 "B.Adhes" user "B.Adhesive")
		(13 "F.Paste" user "Package Geometry/Pastemask Top")
		(15 "B.Paste" user "Package Geometry/Pastemask Bottom")
		(5 "F.SilkS" user "Ref Des/Silkscreen Top")
		(7 "B.SilkS" user "Ref Des/Silkscreen Bottom")
		(1 "F.Mask" user "Board Geometry/Soldermask Top")
		(3 "B.Mask" user "Board Geometry/Soldermask Bottom")
		(17 "Dwgs.User" user "User.Drawings")
		(19 "Cmts.User" user "User.Comments")
		(21 "Eco1.User" user "User.Eco1")
		(23 "Eco2.User" user "User.Eco2")
		(25 "Edge.Cuts" user "Board Geometry/Outline")
		(27 "Margin" user)
		(31 "F.CrtYd" user "Package Geometry/Place Bound Top")
		(29 "B.CrtYd" user "Package Geometry/Place Bound Bottom")
		(35 "F.Fab" user "Ref Des/Assembly Top")
		(33 "B.Fab" user "Ref Des/Assembly Bottom")
	)
	(footprint ""
		(layer "F.Cu")
		(at 261.94258 -77.485748 -90)
		(property "Reference" "PC2279"
			(at 0 0 270)
			(layer "F.SilkS")
			(hide yes)
			(effects
				(font
					(size 1.27 1.27)
				)
			)
		)
		(property "Value" ""
			(at 0 0 270)
			(layer "F.Fab")
			(effects
				(font
					(size 1.27 1.27)
				)
			)
		)
		(duplicate_pad_numbers_are_jumpers no)
		(fp_line
			(start -0.7874 0.4064)
			(end -0.7874 -0.4064)
			(stroke
				(width 0.1524)
				(type default)
			)
			(layer "F.SilkS")
		)
		(fp_line
			(start 0.7874 0.4064)
			(end -0.7874 0.4064)
			(stroke
				(width 0.1524)
				(type default)
			)
			(layer "F.SilkS")
		)
		(fp_line
			(start -0.7874 -0.4064)
			(end 0.7874 -0.4064)
			(stroke
				(width 0.1524)
				(type default)
			)
			(layer "F.SilkS")
		)
		(fp_line
			(start 0.7874 -0.4064)
			(end 0.7874 0.4064)
			(stroke
				(width 0.1524)
				(type default)
			)
			(layer "F.SilkS")
		)
		(fp_line
			(start -0.67945 0.3048)
			(end -0.67945 -0.305054)
			(stroke
				(width 0.1)
				(type default)
			)
			(layer "F.Fab")
		)
		(fp_line
			(start -0.12065 0.3048)
			(end -0.67945 0.3048)
			(stroke
				(width 0.1)
				(type default)
			)
			(layer "F.Fab")
		)
		(fp_line
			(start 0.120396 0.3048)
			(end 0.120396 0.2794)
			(stroke
				(width 0.1)
				(type default)
			)
			(layer "F.Fab")
		)
		(fp_line
			(start 0.67945 0.3048)
			(end 0.120396 0.3048)
			(stroke
				(width 0.1)
				(type default)
			)
			(layer "F.Fab")
		)
		(fp_line
			(start -0.12065 0.2794)
			(end -0.12065 0.3048)
			(stroke
				(width 0.1)
				(type default)
			)
			(layer "F.Fab")
		)
		(fp_line
			(start 0.120396 0.2794)
			(end -0.12065 0.2794)
			(stroke
				(width 0.1)
				(type default)
			)
			(layer "F.Fab")
		)
		(fp_line
			(start -0.12065 -0.2794)
			(end 0.12065 -0.2794)
			(stroke
				(width 0.1)
				(type default)
			)
			(layer "F.Fab")
		)
		(fp_line
			(start 0.12065 -0.2794)
			(end 0.12065 -0.3048)
			(stroke
				(width 0.1)
				(type default)
			)
			(layer "F.Fab")
		)
		(fp_line
			(start 0.12065 -0.3048)
			(end 0.67945 -0.3048)
			(stroke
				(width 0.1)
				(type default)
			)
			(layer "F.Fab")
		)
		(fp_line
			(start 0.67945 -0.3048)
			(end 0.67945 0.3048)
			(stroke
				(width 0.1)
				(type default)
			)
			(layer "F.Fab")
		)
		(fp_line
			(start -0.67945 -0.305054)
			(end -0.12065 -0.305054)
			(stroke
				(width 0.1)
				(type default)
			)
			(layer "F.Fab")
		)
		(fp_line
			(start -0.12065 -0.305054)
			(end -0.12065 -0.2794)
			(stroke
				(width 0.1)
				(type default)
			)
			(layer "F.Fab")
		)
		(pad "1" smd circle
			(at -0.40005 0 270)
			(size 0 0)
			(layers "F.Cu" "F.Mask" "F.Paste")
			(net "SH_P1V05_PCH_AUX_P")
		)
		(pad "2" smd circle
			(at 0.40005 0 270)
			(size 0 0)
			(layers "F.Cu" "F.Mask" "F.Paste")
			(net "SH_P1V05_PCH_AUX_N")
		)
	)
	(footprint ""
		(layer "F.Cu")
		(at 271.312894 -64.457834 180)
		(property "Reference" "PC117"
			(at 0 0 180)
			(layer "F.SilkS")
			(hide yes)
			(effects
				(font
					(size 1.27 1.27)
				)
			)
		)
		(property "Value" ""
			(at 0 0 180)
			(layer "F.Fab")
			(effects
				(font
					(size 1.27 1.27)
				)
			)
		)
		(duplicate_pad_numbers_are_jumpers no)
		(fp_line
			(start 4.53898 2.15011)
			(end -4.53898 2.15011)
			(stroke
				(width 0.1524)
				(type default)
			)
			(layer "F.SilkS")
		)
		(fp_line
			(start 4.53898 -2.15011)
			(end 4.53898 2.15011)
			(stroke
				(width 0.1524)
				(type default)
			)
			(layer "F.SilkS")
		)
		(fp_line
			(start -4.53898 2.15011)
			(end -4.53898 -2.15011)
			(stroke
				(width 0.1524)
				(type default)
			)
			(layer "F.SilkS")
		)
		(fp_line
			(start -4.53898 -2.15011)
			(end 4.53898 -2.15011)
			(stroke
				(width 0.1524)
				(type default)
			)
			(layer "F.SilkS")
		)
		(fp_line
			(start -4.53898 -2.150618)
			(end -4.539742 2.152142)
			(stroke
				(width 0.1524)
				(type default)
			)
			(layer "F.SilkS")
		)
		(fp_line
			(start -4.69138 -2.150618)
			(end -4.692396 2.161032)
			(stroke
				(width 0.1524)
				(type default)
			)
			(layer "F.SilkS")
		)
		(fp_line
			(start -4.83108 2.150364)
			(end -4.447794 2.149348)
			(stroke
				(width 0.1524)
				(type default)
			)
			(layer "F.SilkS")
		)
		(fp_line
			(start -4.84378 -2.150618)
			(end -4.53898 -2.150618)
			(stroke
				(width 0.1524)
				(type default)
			)
			(layer "F.SilkS")
		)
		(fp_line
			(start -4.84378 -2.150618)
			(end -4.842256 2.163064)
			(stroke
				(width 0.1524)
				(type default)
			)
			(layer "F.SilkS")
		)
		(fp_line
			(start 3.64998 2.15011)
			(end -3.64998 2.15011)
			(stroke
				(width 0.1)
				(type default)
			)
			(layer "F.Fab")
		)
		(fp_line
			(start 3.64998 -2.15011)
			(end 3.64998 2.15011)
			(stroke
				(width 0.1)
				(type default)
			)
			(layer "F.Fab")
		)
		(fp_line
			(start -3.64998 2.15011)
			(end -3.64998 -2.15011)
			(stroke
				(width 0.1)
				(type default)
			)
			(layer "F.Fab")
		)
		(fp_line
			(start -3.64998 -2.15011)
			(end 3.64998 -2.15011)
			(stroke
				(width 0.1)
				(type default)
			)
			(layer "F.Fab")
		)
		(fp_text user "-"
			(at 5.788914 -0.077216 180)
			(unlocked yes)
			(layer "F.SilkS")
			(effects
				(font
					(size 1.905 1.4224)
					(thickness 0.1524)
				)
				(justify left)
			)
		)
		(fp_text user "+"
			(at -4.894326 -3.203956 180)
			(unlocked yes)
			(layer "F.SilkS")
			(effects
				(font
					(size 1.905 1.4224)
					(thickness 0.1524)
				)
				(justify left)
			)
		)
		(fp_text user "-"
			(at 4.313174 -0.094488 180)
			(unlocked yes)
			(layer "F.Fab")
			(effects
				(font
					(size 1.905 1.4224)
					(thickness 0.1524)
				)
				(justify left)
			)
		)
		(fp_text user "+"
			(at -6.214872 -0.337058 180)
			(unlocked yes)
			(layer "F.Fab")
			(effects
				(font
					(size 1.905 1.4224)
					(thickness 0.1524)
				)
				(justify left)
			)
		)
		(pad "1" smd rect
			(at -3.199892 0 180)
			(size 2.413 2.8194)
			(layers "F.Cu" "F.Mask" "F.Paste")
			(net "P1V05_PCH_AUX")
		)
		(pad "2" smd rect
			(at 3.199892 0 180)
			(size 2.413 2.8194)
			(layers "F.Cu" "F.Mask" "F.Paste")
			(net "GND")
		)
	)
)
